# T6G (Grand Teton) — schematic netlist excerpt (pin names and nets, part order shuffled) for the footprints in the layout excerpt that follows; sources: Cadence DE-HDL packaged netlist, KiCad conversion of 04192023_DAF0TMB3IC0_F0TG_MB_C_brd_V02_OCP.brd

C2297  Q_CAP  22UF 4V 20% X6S  pkg C0402  page 73 : A = PVDDCR_CPU0_P1 ; B = GND
C6537  Q_CAP_DIFFBUS  DIFF BUS_0.22UF 6.3V 20% X6S  pkg C0201  page 286 : \1\ = P5E_CPU0_P1_TX_BUF_C_DP<2> ; \2\ = P5E_CPU0_P1_TX_BUF_DP<2>
PC615_3  Q_CAP  22UF 4V 20% X6S  pkg C0805  page 199 : A = PVDDCR_SOC_P0 ; B = GND

(kicad_pcb
	(version 20260206)
	(generator "pcbnew")
	(generator_version "10.0")
	(general
		(thickness 1.6)
		(legacy_teardrops no)
	)
	(paper "A4")
	(title_block
		(title "04192023_DAF0TMB3IC0_F0TG_MB_C_brd_V02_OCP.brd")
		(comment 1 "Grand Teton / footprints 7940-7942 of 8354")
	)
	(layers
		(0 "F.Cu" signal "TOP")
		(4 "In1.Cu" signal "GND")
		(6 "In2.Cu" signal "IN1")
		(8 "In3.Cu" signal "GND1")
		(10 "In4.Cu" signal "IN2")
		(12 "In5.Cu" signal "GND2")
		(14 "In6.Cu" signal "IN3")
		(16 "In7.Cu" signal "GND3")
		(18 "In8.Cu" signal "VCC")
		(20 "In9.Cu" signal "VCC1")
		(22 "In10.Cu" signal "GND4")
		(24 "In11.Cu" signal "IN4")
		(26 "In12.Cu" signal "GND5")
		(28 "In13.Cu" signal "IN5")
		(30 "In14.Cu" signal "GND6")
		(32 "In15.Cu" signal "IN6")
		(34 "In16.Cu" signal "GND7")
		(2 "B.Cu" signal "BOTTOM")
		(9 "F.Adhes" user "F.Adhesive")
		(11 "B.Adhes" user "B.Adhesive")
		(13 "F.Paste" user "Package Geometry/Pastemask Top")
		(15 "B.Paste" user "Package Geometry/Pastemask Bottom")
		(5 "F.SilkS" user "Ref Des/Silkscreen Top")
		(7 "B.SilkS" user "Ref Des/Silkscreen Bottom")
		(1 "F.Mask" user "Board Geometry/Soldermask Top")
		(3 "B.Mask" user "Board Geometry/Soldermask Bottom")
		(17 "Dwgs.User" user "User.Drawings")
		(19 "Cmts.User" user "User.Comments")
		(21 "Eco1.User" user "User.Eco1")
		(23 "Eco2.User" user "User.Eco2")
		(25 "Edge.Cuts" user "Board Geometry/Outline")
		(27 "Margin" user)
		(31 "F.CrtYd" user "Package Geometry/Place Bound Top")
		(29 "B.CrtYd" user "Package Geometry/Place Bound Bottom")
		(35 "F.Fab" user "Ref Des/Assembly Top")
		(33 "B.Fab" user "Ref Des/Assembly Bottom")
	)
	(footprint ""
		(layer "B.Cu")
		(at 117.896386 -249.368564)
		(property "Reference" "C2297"
			(at 0 0 0)
			(layer "B.SilkS")
			(hide yes)
			(effects
				(font
					(size 1.27 1.27)
				)
				(justify mirror)
			)
		)
		(property "Value" ""
			(at 0 0 0)
			(layer "B.Fab")
			(effects
				(font
					(size 1.27 1.27)
				)
				(justify mirror)
			)
		)
		(duplicate_pad_numbers_are_jumpers no)
		(fp_line
			(start -0.7874 -0.4064)
			(end -0.7874 0.4064)
			(stroke
				(width 0.1524)
				(type default)
			)
			(layer "B.SilkS")
		)
		(fp_line
			(start -0.7874 0.4064)
			(end 0.7874 0.4064)
			(stroke
				(width 0.1524)
				(type default)
			)
			(layer "B.SilkS")
		)
		(fp_line
			(start 0.7874 -0.4064)
			(end -0.7874 -0.4064)
			(stroke
				(width 0.1524)
				(type default)
			)
			(layer "B.SilkS")
		)
		(fp_line
			(start 0.7874 0.4064)
			(end 0.7874 -0.4064)
			(stroke
				(width 0.1524)
				(type default)
			)
			(layer "B.SilkS")
		)
		(fp_line
			(start -0.67945 -0.3048)
			(end -0.67945 0.3048)
			(stroke
				(width 0.1)
				(type default)
			)
			(layer "B.Fab")
		)
		(fp_line
			(start -0.67945 0.3048)
			(end -0.120396 0.3048)
			(stroke
				(width 0.1)
				(type default)
			)
			(layer "B.Fab")
		)
		(fp_line
			(start -0.12065 -0.3048)
			(end -0.67945 -0.3048)
			(stroke
				(width 0.1)
				(type default)
			)
			(layer "B.Fab")
		)
		(fp_line
			(start -0.12065 -0.2794)
			(end -0.12065 -0.3048)
			(stroke
				(width 0.1)
				(type default)
			)
			(layer "B.Fab")
		)
		(fp_line
			(start -0.120396 0.2794)
			(end 0.12065 0.2794)
			(stroke
				(width 0.1)
				(type default)
			)
			(layer "B.Fab")
		)
		(fp_line
			(start -0.120396 0.3048)
			(end -0.120396 0.2794)
			(stroke
				(width 0.1)
				(type default)
			)
			(layer "B.Fab")
		)
		(fp_line
			(start 0.12065 -0.305054)
			(end 0.12065 -0.2794)
			(stroke
				(width 0.1)
				(type default)
			)
			(layer "B.Fab")
		)
		(fp_line
			(start 0.12065 -0.2794)
			(end -0.12065 -0.2794)
			(stroke
				(width 0.1)
				(type default)
			)
			(layer "B.Fab")
		)
		(fp_line
			(start 0.12065 0.2794)
			(end 0.12065 0.3048)
			(stroke
				(width 0.1)
				(type default)
			)
			(layer "B.Fab")
		)
		(fp_line
			(start 0.12065 0.3048)
			(end 0.67945 0.3048)
			(stroke
				(width 0.1)
				(type default)
			)
			(layer "B.Fab")
		)
		(fp_line
			(start 0.67945 -0.305054)
			(end 0.12065 -0.305054)
			(stroke
				(width 0.1)
				(type default)
			)
			(layer "B.Fab")
		)
		(fp_line
			(start 0.67945 0.3048)
			(end 0.67945 -0.305054)
			(stroke
				(width 0.1)
				(type default)
			)
			(layer "B.Fab")
		)
		(pad "1" smd circle
			(at 0.40005 0 180)
			(size 0 0)
			(layers "B.Cu" "B.Mask" "B.Paste")
			(net "PVDDCR_CPU0_P1")
		)
		(pad "2" smd circle
			(at -0.40005 0 180)
			(size 0 0)
			(layers "B.Cu" "B.Mask" "B.Paste")
			(net "GND")
		)
	)
	(footprint ""
		(layer "B.Cu")
		(at 312.341006 -416.899344 90)
		(property "Reference" "C6537"
			(at 0 0 90)
			(layer "B.SilkS")
			(hide yes)
			(effects
				(font
					(size 1.27 1.27)
				)
				(justify mirror)
			)
		)
		(property "Value" ""
			(at 0 0 90)
			(layer "B.Fab")
			(effects
				(font
					(size 1.27 1.27)
				)
				(justify mirror)
			)
		)
		(duplicate_pad_numbers_are_jumpers no)
		(fp_line
			(start 0.299974 -0.150114)
			(end -0.299974 -0.150114)
			(stroke
				(width 0.1)
				(type default)
			)
			(layer "B.Fab")
		)
		(fp_line
			(start -0.299974 -0.150114)
			(end -0.299974 0.150114)
			(stroke
				(width 0.1)
				(type default)
			)
			(layer "B.Fab")
		)
		(fp_line
			(start 0.299974 0.150114)
			(end 0.299974 -0.150114)
			(stroke
				(width 0.1)
				(type default)
			)
			(layer "B.Fab")
		)
		(fp_line
			(start -0.299974 0.150114)
			(end 0.299974 0.150114)
			(stroke
				(width 0.1)
				(type default)
			)
			(layer "B.Fab")
		)
		(pad "1" smd rect
			(at 0.2667 0 270)
			(size 0.3048 0.381)
			(layers "B.Cu" "B.Mask" "B.Paste")
			(net "P5E_CPU0_P1_TX_BUF_C_DP<2>")
		)
		(pad "2" smd rect
			(at -0.2667 0 270)
			(size 0.3048 0.381)
			(layers "B.Cu" "B.Mask" "B.Paste")
			(net "P5E_CPU0_P1_TX_BUF_DP<2>")
		)
	)
	(footprint ""
		(layer "B.Cu")
		(at 419.062916 -172.407072 90)
		(property "Reference" "PC615_3"
			(at 0 0 90)
			(layer "B.SilkS")
			(hide yes)
			(effects
				(font
					(size 1.27 1.27)
				)
				(justify mirror)
			)
		)
		(property "Value" ""
			(at 0 0 90)
			(layer "B.Fab")
			(effects
				(font
					(size 1.27 1.27)
				)
				(justify mirror)
			)
		)
		(duplicate_pad_numbers_are_jumpers no)
		(fp_line
			(start 1.524 -0.762)
			(end -1.524 -0.762)
			(stroke
				(width 0.1524)
				(type default)
			)
			(layer "B.SilkS")
		)
		(fp_line
			(start -1.524 -0.762)
			(end -1.524 0.762)
			(stroke
				(width 0.1524)
				(type default)
			)
			(layer "B.SilkS")
		)
		(fp_line
			(start 1.524 0.762)
			(end 1.524 -0.762)
			(stroke
				(width 0.1524)
				(type default)
			)
			(layer "B.SilkS")
		)
		(fp_line
			(start -1.524 0.762)
			(end 1.524 0.762)
			(stroke
				(width 0.1524)
				(type default)
			)
			(layer "B.SilkS")
		)
		(fp_line
			(start 1.1049 -0.724916)
			(end 1.1049 0.724916)
			(stroke
				(width 0.1)
				(type default)
			)
			(layer "B.Fab")
		)
		(fp_line
			(start -1.1049 -0.724916)
			(end 1.1049 -0.724916)
			(stroke
				(width 0.1)
				(type default)
			)
			(layer "B.Fab")
		)
		(fp_line
			(start 1.1049 0.724916)
			(end -1.1049 0.724916)
			(stroke
				(width 0.1)
				(type default)
			)
			(layer "B.Fab")
		)
		(fp_line
			(start -1.1049 0.724916)
			(end -1.1049 -0.724916)
			(stroke
				(width 0.1)
				(type default)
			)
			(layer "B.Fab")
		)
		(pad "1" smd rect
			(at 0.889 0 90)
			(size 1.016 1.27)
			(layers "B.Cu" "B.Mask" "B.Paste")
			(net "PVDDCR_SOC_P0")
		)
		(pad "2" smd rect
			(at -0.889 0 90)
			(size 1.016 1.27)
			(layers "B.Cu" "B.Mask" "B.Paste")
			(net "GND")
		)
	)
)
